# BASEBOARD_FAB2 (Tioga Pass) — schematic netlist excerpt (pin names and nets, part order shuffled) for the footprints in the layout excerpt that follows; sources: Cadence DE-HDL packaged netlist, KiCad conversion of Wiwynn_Tioga_Pass_MB.brd

R2P11  RES  1.00K 1% EMPTY  pkg 0402  page 170 : A = FM_PMBUS_ALERT_BUF_EN_N ; B = GND

U1L2  TTL1G86  74AHCT1G86 IC  pkg SOTLF  page 175
  A  = PWRGD_P3V3_R
  B  = FP_PWR_ID_LED_N
  Y  = FP_ID_LED_P5V_STBY_N

C5G114  CAP_A  22.0UF 4V 20% X6S  pkg 0603V  page 243 : A = PVDDQ_KLM ; B = GND

(kicad_pcb
	(version 20260206)
	(generator "pcbnew")
	(generator_version "10.0")
	(general
		(thickness 1.6)
		(legacy_teardrops no)
	)
	(paper "A4")
	(title_block
		(title "Wiwynn_Tioga_Pass_MB.brd")
		(comment 1 "Tioga Pass / footprints 4441-4443 of 4770")
	)
	(layers
		(0 "F.Cu" signal "TOP")
		(4 "In1.Cu" signal "L2GND")
		(6 "In2.Cu" signal "L3")
		(8 "In3.Cu" signal "L4GND")
		(10 "In4.Cu" signal "L5")
		(12 "In5.Cu" signal "L6GND")
		(14 "In6.Cu" signal "L7VCC")
		(16 "In7.Cu" signal "L8VCC")
		(18 "In8.Cu" signal "L9GND")
		(20 "In9.Cu" signal "L10")
		(22 "In10.Cu" signal "L11GND")
		(24 "In11.Cu" signal "L12")
		(26 "In12.Cu" signal "L13GND")
		(2 "B.Cu" signal "BOTTOM")
		(9 "F.Adhes" user "F.Adhesive")
		(11 "B.Adhes" user "B.Adhesive")
		(13 "F.Paste" user "Package Geometry/Pastemask Top")
		(15 "B.Paste" user "Package Geometry/Pastemask Bottom")
		(5 "F.SilkS" user "Ref Des/Silkscreen Top")
		(7 "B.SilkS" user "Ref Des/Silkscreen Bottom")
		(1 "F.Mask" user "Board Geometry/Soldermask Top")
		(3 "B.Mask" user "Board Geometry/Soldermask Bottom")
		(17 "Dwgs.User" user "User.Drawings")
		(19 "Cmts.User" user "User.Comments")
		(21 "Eco1.User" user "User.Eco1")
		(23 "Eco2.User" user "User.Eco2")
		(25 "Edge.Cuts" user "Board Geometry/Outline")
		(27 "Margin" user)
		(31 "F.CrtYd" user "Package Geometry/Place Bound Top")
		(29 "B.CrtYd" user "Package Geometry/Place Bound Bottom")
		(35 "F.Fab" user "Ref Des/Assembly Top")
		(33 "B.Fab" user "Ref Des/Assembly Bottom")
	)
	(footprint ""
		(layer "B.Cu")
		(at 489.189014 -153.924 90)
		(property "Reference" "U1L2"
			(at -2.633726 2.058416 270)
			(unlocked yes)
			(layer "B.SilkS")
			(effects
				(font
					(size 0.7874 0.5842)
					(thickness 0.1524)
				)
				(justify left mirror)
			)
		)
		(property "Value" ""
			(at 0 0 90)
			(layer "B.Fab")
			(effects
				(font
					(size 1.27 1.27)
				)
				(justify mirror)
			)
		)
		(duplicate_pad_numbers_are_jumpers no)
		(fp_circle
			(center 0.4699 -0.8382)
			(end 0.4699 -0.7112)
			(stroke
				(width 0.254)
				(type default)
			)
			(fill no)
			(layer "B.SilkS")
		)
		(fp_poly
			(pts
				(xy -0.21463 -0.450088) (xy -1.56337 -0.450088) (xy -1.56337 1.75006) (xy -0.21463 1.75006)
			)
			(stroke
				(width 0)
				(type default)
			)
			(fill no)
			(layer "B.CrtYd")
		)
		(fp_line
			(start -0.21463 -0.450088)
			(end -1.56337 -0.450088)
			(stroke
				(width 0.1)
				(type default)
			)
			(layer "B.Fab")
		)
		(fp_line
			(start -1.56337 -0.450088)
			(end -1.56337 1.75006)
			(stroke
				(width 0.1)
				(type default)
			)
			(layer "B.Fab")
		)
		(fp_line
			(start -0.21463 1.75006)
			(end -0.21463 -0.450088)
			(stroke
				(width 0.1)
				(type default)
			)
			(layer "B.Fab")
		)
		(fp_line
			(start -1.56337 1.75006)
			(end -0.21463 1.75006)
			(stroke
				(width 0.1)
				(type default)
			)
			(layer "B.Fab")
		)
		(fp_circle
			(center 0.4699 -0.8382)
			(end 0.4699 -0.7112)
			(stroke
				(width 0.254)
				(type default)
			)
			(fill no)
			(layer "B.Fab")
		)
		(pad "1" smd rect
			(at 0 0 270)
			(size 1.016 0.381)
			(layers "B.Cu" "B.Mask" "B.Paste")
			(net "PWRGD_P3V3_R")
		)
		(pad "2" smd rect
			(at 0 0.649986 270)
			(size 1.016 0.381)
			(layers "B.Cu" "B.Mask" "B.Paste")
			(net "FP_PWR_ID_LED_N")
		)
		(pad "3" smd rect
			(at 0 1.299972 270)
			(size 1.016 0.381)
			(layers "B.Cu" "B.Mask" "B.Paste")
			(net "GND")
		)
		(pad "4" smd rect
			(at -1.778 1.299972 270)
			(size 1.016 0.381)
			(layers "B.Cu" "B.Mask" "B.Paste")
			(net "FP_ID_LED_P5V_STBY_N")
		)
		(pad "5" smd rect
			(at -1.778 0 270)
			(size 1.016 0.381)
			(layers "B.Cu" "B.Mask" "B.Paste")
			(net "P5V_STBY")
		)
	)
	(footprint ""
		(layer "B.Cu")
		(at 80.731868 -140.208 -90)
		(property "Reference" "C5G114"
			(at -1.14681 0.76708 0)
			(unlocked yes)
			(layer "B.SilkS")
			(effects
				(font
					(size 0.7874 0.5842)
					(thickness 0.1524)
				)
				(justify mirror)
			)
		)
		(property "Value" ""
			(at 0 0 90)
			(layer "B.Fab")
			(effects
				(font
					(size 1.27 1.27)
				)
				(justify mirror)
			)
		)
		(duplicate_pad_numbers_are_jumpers no)
		(fp_rect
			(start 0.4953 1.6002)
			(end -0.4953 -0.2032)
			(stroke
				(width 0)
				(type default)
			)
			(fill no)
			(layer "B.CrtYd")
		)
		(fp_line
			(start -0.4953 1.6002)
			(end 0.4953 1.6002)
			(stroke
				(width 0.1)
				(type default)
			)
			(layer "B.Fab")
		)
		(fp_line
			(start 0.4953 1.6002)
			(end 0.4953 -0.2032)
			(stroke
				(width 0.1)
				(type default)
			)
			(layer "B.Fab")
		)
		(fp_line
			(start -0.4953 -0.2032)
			(end -0.4953 1.6002)
			(stroke
				(width 0.1)
				(type default)
			)
			(layer "B.Fab")
		)
		(fp_line
			(start 0.4953 -0.2032)
			(end -0.4953 -0.2032)
			(stroke
				(width 0.1)
				(type default)
			)
			(layer "B.Fab")
		)
		(pad "1" smd rect
			(at 0 0 90)
			(size 0.762 0.889)
			(layers "B.Cu" "B.Mask" "B.Paste")
			(net "PVDDQ_KLM")
		)
		(pad "2" smd rect
			(at 0 1.397 90)
			(size 0.762 0.889)
			(layers "B.Cu" "B.Mask" "B.Paste")
			(net "GND")
		)
		(zone
			(layer "B.Cu")
			(hatch none 0.5)
			(connect_pads
				(clearance 0)
			)
			(min_thickness 0.25)
			(keepout
				(tracks not_allowed)
				(vias allowed)
				(pads allowed)
				(copperpour not_allowed)
				(footprints allowed)
			)
			(placement
				(enabled no)
				(sheetname "")
			)
			(fill
				(thermal_gap 0.5)
				(thermal_bridge_width 0.5)
				(island_removal_mode 0)
			)
			(polygon
				(pts
					(xy 79.779368 -139.827) (xy 80.287368 -139.827) (xy 80.287368 -140.589) (xy 79.779368 -140.589)
				)
			)
		)
	)
	(footprint ""
		(layer "B.Cu")
		(at 422.2242 -83.1342 -90)
		(property "Reference" "R2P11"
			(at 0 0 90)
			(layer "B.SilkS")
			(hide yes)
			(effects
				(font
					(size 1.27 1.27)
				)
				(justify mirror)
			)
		)
		(property "Value" ""
			(at 0 0 90)
			(layer "B.Fab")
			(effects
				(font
					(size 1.27 1.27)
				)
				(justify mirror)
			)
		)
		(duplicate_pad_numbers_are_jumpers no)
		(fp_poly
			(pts
				(xy 0.2794 -0.1016) (xy -0.2794 -0.1016) (xy -0.2794 0.9906) (xy 0.2794 0.9906)
			)
			(stroke
				(width 0)
				(type default)
			)
			(fill no)
			(layer "B.CrtYd")
		)
		(fp_line
			(start -0.2794 0.9906)
			(end -0.2794 -0.1016)
			(stroke
				(width 0.1)
				(type default)
			)
			(layer "B.Fab")
		)
		(fp_line
			(start 0.2794 0.9906)
			(end -0.2794 0.9906)
			(stroke
				(width 0.1)
				(type default)
			)
			(layer "B.Fab")
		)
		(fp_line
			(start -0.2794 -0.1016)
			(end 0.2794 -0.1016)
			(stroke
				(width 0.1)
				(type default)
			)
			(layer "B.Fab")
		)
		(fp_line
			(start 0.2794 -0.1016)
			(end 0.2794 0.9906)
			(stroke
				(width 0.1)
				(type default)
			)
			(layer "B.Fab")
		)
		(pad "1" smd rect
			(at 0 0 90)
			(size 0.508 0.508)
			(layers "B.Cu" "B.Mask" "B.Paste")
			(net "FM_PMBUS_ALERT_BUF_EN_N")
		)
		(pad "2" smd rect
			(at 0 0.889 90)
			(size 0.508 0.508)
			(layers "B.Cu" "B.Mask" "B.Paste")
			(net "GND")
		)
		(zone
			(layer "B.Cu")
			(hatch none 0.5)
			(connect_pads
				(clearance 0)
			)
			(min_thickness 0.25)
			(keepout
				(tracks not_allowed)
				(vias allowed)
				(pads allowed)
				(copperpour not_allowed)
				(footprints allowed)
			)
			(placement
				(enabled no)
				(sheetname "")
			)
			(fill
				(thermal_gap 0.5)
				(thermal_bridge_width 0.5)
				(island_removal_mode 0)
			)
			(polygon
				(pts
					(xy 421.5892 -82.8802) (xy 421.5892 -83.3882) (xy 421.9702 -83.3882) (xy 421.9702 -82.8802)
				)
			)
		)
		(zone
			(layer "B.Cu")
			(hatch none 0.5)
			(connect_pads
				(clearance 0)
			)
			(min_thickness 0.25)
			(keepout
				(tracks allowed)
				(vias not_allowed)
				(pads allowed)
				(copperpour not_allowed)
				(footprints allowed)
			)
			(placement
				(enabled no)
				(sheetname "")
			)
			(fill
				(thermal_gap 0.5)
				(thermal_bridge_width 0.5)
				(island_removal_mode 0)
			)
			(polygon
				(pts
					(xy 421.9702 -82.8802) (xy 421.9702 -83.3882) (xy 421.5892 -83.3882) (xy 421.5892 -82.8802)
				)
			)
		)
	)
)
